# BASEBOARD_FAB2 (Tioga Pass) — schematic netlist excerpt (pin names and nets, part order shuffled) for the footprints in the layout excerpt that follows; sources: Cadence DE-HDL packaged netlist, KiCad conversion of Wiwynn_Tioga_Pass_MB.brd

R25W93  RES  0 5.0% CHIP  pkg 0603  page 149 : A = P3V3_STBY ; B = VCC_DACAV3V3
R6L9  RES  10.0K 1% CHIP  pkg 0402  page 222 : A = P3V3 ; B = PWRGD_PVTT_DEF_CPU0_R
R2W5  RES  0.0 5% CHIP  pkg 0402  page 145 : A = FM_PMBUS_ALERT_BUF_EN_R3_N ; B = FM_PMBUS_ALERT_BUF_EN_N

(kicad_pcb
	(version 20260206)
	(generator "pcbnew")
	(generator_version "10.0")
	(general
		(thickness 1.6)
		(legacy_teardrops no)
	)
	(paper "A4")
	(title_block
		(title "Wiwynn_Tioga_Pass_MB.brd")
		(comment 1 "Tioga Pass / footprints 3643-3645 of 4770")
	)
	(layers
		(0 "F.Cu" signal "TOP")
		(4 "In1.Cu" signal "L2GND")
		(6 "In2.Cu" signal "L3")
		(8 "In3.Cu" signal "L4GND")
		(10 "In4.Cu" signal "L5")
		(12 "In5.Cu" signal "L6GND")
		(14 "In6.Cu" signal "L7VCC")
		(16 "In7.Cu" signal "L8VCC")
		(18 "In8.Cu" signal "L9GND")
		(20 "In9.Cu" signal "L10")
		(22 "In10.Cu" signal "L11GND")
		(24 "In11.Cu" signal "L12")
		(26 "In12.Cu" signal "L13GND")
		(2 "B.Cu" signal "BOTTOM")
		(9 "F.Adhes" user "F.Adhesive")
		(11 "B.Adhes" user "B.Adhesive")
		(13 "F.Paste" user "Package Geometry/Pastemask Top")
		(15 "B.Paste" user "Package Geometry/Pastemask Bottom")
		(5 "F.SilkS" user "Ref Des/Silkscreen Top")
		(7 "B.SilkS" user "Ref Des/Silkscreen Bottom")
		(1 "F.Mask" user "Board Geometry/Soldermask Top")
		(3 "B.Mask" user "Board Geometry/Soldermask Bottom")
		(17 "Dwgs.User" user "User.Drawings")
		(19 "Cmts.User" user "User.Comments")
		(21 "Eco1.User" user "User.Eco1")
		(23 "Eco2.User" user "User.Eco2")
		(25 "Edge.Cuts" user "Board Geometry/Outline")
		(27 "Margin" user)
		(31 "F.CrtYd" user "Package Geometry/Place Bound Top")
		(29 "B.CrtYd" user "Package Geometry/Place Bound Bottom")
		(35 "F.Fab" user "Ref Des/Assembly Top")
		(33 "B.Fab" user "Ref Des/Assembly Bottom")
	)
	(footprint ""
		(layer "B.Cu")
		(at 424.815 -27.0002 180)
		(property "Reference" "R2W5"
			(at 0.8382 -0.67818 180)
			(unlocked yes)
			(layer "B.SilkS")
			(effects
				(font
					(size 0.4064 0.254)
					(thickness 0.1524)
				)
				(justify left mirror)
			)
		)
		(property "Value" ""
			(at 0 0 0)
			(layer "B.Fab")
			(effects
				(font
					(size 1.27 1.27)
				)
				(justify mirror)
			)
		)
		(duplicate_pad_numbers_are_jumpers no)
		(fp_poly
			(pts
				(xy 0.2794 -0.1016) (xy -0.2794 -0.1016) (xy -0.2794 0.9906) (xy 0.2794 0.9906)
			)
			(stroke
				(width 0)
				(type default)
			)
			(fill no)
			(layer "B.CrtYd")
		)
		(fp_line
			(start 0.2794 0.9906)
			(end -0.2794 0.9906)
			(stroke
				(width 0.1)
				(type default)
			)
			(layer "B.Fab")
		)
		(fp_line
			(start 0.2794 -0.1016)
			(end 0.2794 0.9906)
			(stroke
				(width 0.1)
				(type default)
			)
			(layer "B.Fab")
		)
		(fp_line
			(start -0.2794 0.9906)
			(end -0.2794 -0.1016)
			(stroke
				(width 0.1)
				(type default)
			)
			(layer "B.Fab")
		)
		(fp_line
			(start -0.2794 -0.1016)
			(end 0.2794 -0.1016)
			(stroke
				(width 0.1)
				(type default)
			)
			(layer "B.Fab")
		)
		(pad "1" smd rect
			(at 0 0)
			(size 0.508 0.508)
			(layers "B.Cu" "B.Mask" "B.Paste")
			(net "FM_PMBUS_ALERT_BUF_EN_R3_N")
		)
		(pad "2" smd rect
			(at 0 0.889)
			(size 0.508 0.508)
			(layers "B.Cu" "B.Mask" "B.Paste")
			(net "FM_PMBUS_ALERT_BUF_EN_N")
		)
		(zone
			(layer "B.Cu")
			(hatch none 0.5)
			(connect_pads
				(clearance 0)
			)
			(min_thickness 0.25)
			(keepout
				(tracks not_allowed)
				(vias allowed)
				(pads allowed)
				(copperpour not_allowed)
				(footprints allowed)
			)
			(placement
				(enabled no)
				(sheetname "")
			)
			(fill
				(thermal_gap 0.5)
				(thermal_bridge_width 0.5)
				(island_removal_mode 0)
			)
			(polygon
				(pts
					(xy 424.561 -27.6352) (xy 425.069 -27.6352) (xy 425.069 -27.2542) (xy 424.561 -27.2542)
				)
			)
		)
		(zone
			(layer "B.Cu")
			(hatch none 0.5)
			(connect_pads
				(clearance 0)
			)
			(min_thickness 0.25)
			(keepout
				(tracks allowed)
				(vias not_allowed)
				(pads allowed)
				(copperpour not_allowed)
				(footprints allowed)
			)
			(placement
				(enabled no)
				(sheetname "")
			)
			(fill
				(thermal_gap 0.5)
				(thermal_bridge_width 0.5)
				(island_removal_mode 0)
			)
			(polygon
				(pts
					(xy 424.561 -27.2542) (xy 425.069 -27.2542) (xy 425.069 -27.6352) (xy 424.561 -27.6352)
				)
			)
		)
	)
	(footprint ""
		(layer "B.Cu")
		(at 185.42 -145.923 -90)
		(property "Reference" "R6L9"
			(at 0 0 90)
			(layer "B.SilkS")
			(hide yes)
			(effects
				(font
					(size 1.27 1.27)
				)
				(justify mirror)
			)
		)
		(property "Value" ""
			(at 0 0 90)
			(layer "B.Fab")
			(effects
				(font
					(size 1.27 1.27)
				)
				(justify mirror)
			)
		)
		(duplicate_pad_numbers_are_jumpers no)
		(fp_rect
			(start -0.2794 0.9906)
			(end 0.2794 -0.1016)
			(stroke
				(width 0)
				(type default)
			)
			(fill no)
			(layer "B.CrtYd")
		)
		(fp_line
			(start -0.2794 0.9906)
			(end -0.2794 -0.1016)
			(stroke
				(width 0.1)
				(type default)
			)
			(layer "B.Fab")
		)
		(fp_line
			(start 0.2794 0.9906)
			(end -0.2794 0.9906)
			(stroke
				(width 0.1)
				(type default)
			)
			(layer "B.Fab")
		)
		(fp_line
			(start -0.2794 -0.1016)
			(end 0.2794 -0.1016)
			(stroke
				(width 0.1)
				(type default)
			)
			(layer "B.Fab")
		)
		(fp_line
			(start 0.2794 -0.1016)
			(end 0.2794 0.9906)
			(stroke
				(width 0.1)
				(type default)
			)
			(layer "B.Fab")
		)
		(pad "1" smd rect
			(at 0 0 90)
			(size 0.508 0.508)
			(layers "B.Cu" "B.Mask" "B.Paste")
			(net "P3V3")
		)
		(pad "2" smd rect
			(at 0 0.889 90)
			(size 0.508 0.508)
			(layers "B.Cu" "B.Mask" "B.Paste")
			(net "PWRGD_PVTT_DEF_CPU0_R")
		)
		(zone
			(layer "B.Cu")
			(hatch none 0.5)
			(connect_pads
				(clearance 0)
			)
			(min_thickness 0.25)
			(keepout
				(tracks allowed)
				(vias not_allowed)
				(pads allowed)
				(copperpour not_allowed)
				(footprints allowed)
			)
			(placement
				(enabled no)
				(sheetname "")
			)
			(fill
				(thermal_gap 0.5)
				(thermal_bridge_width 0.5)
				(island_removal_mode 0)
			)
			(polygon
				(pts
					(xy 184.785 -146.177) (xy 184.785 -145.669) (xy 185.166 -145.669) (xy 185.166 -146.177)
				)
			)
		)
		(zone
			(layer "B.Cu")
			(hatch none 0.5)
			(connect_pads
				(clearance 0)
			)
			(min_thickness 0.25)
			(keepout
				(tracks not_allowed)
				(vias allowed)
				(pads allowed)
				(copperpour not_allowed)
				(footprints allowed)
			)
			(placement
				(enabled no)
				(sheetname "")
			)
			(fill
				(thermal_gap 0.5)
				(thermal_bridge_width 0.5)
				(island_removal_mode 0)
			)
			(polygon
				(pts
					(xy 184.785 -146.177) (xy 184.785 -145.669) (xy 185.166 -145.669) (xy 185.166 -146.177)
				)
			)
		)
	)
	(footprint ""
		(layer "B.Cu")
		(at 400.351498 -34.782506)
		(property "Reference" "R25W93"
			(at -1.01473 0.656336 90)
			(unlocked yes)
			(layer "B.SilkS")
			(effects
				(font
					(size 0.4064 0.254)
					(thickness 0.1524)
				)
				(justify mirror)
			)
		)
		(property "Value" ""
			(at 0 0 0)
			(layer "B.Fab")
			(effects
				(font
					(size 1.27 1.27)
				)
				(justify mirror)
			)
		)
		(duplicate_pad_numbers_are_jumpers no)
		(fp_poly
			(pts
				(xy 0.4953 -0.2032) (xy -0.4953 -0.2032) (xy -0.4953 1.6002) (xy 0.4953 1.6002)
			)
			(stroke
				(width 0)
				(type default)
			)
			(fill no)
			(layer "B.CrtYd")
		)
		(fp_line
			(start -0.4953 -0.2032)
			(end -0.4953 1.6002)
			(stroke
				(width 0.1)
				(type default)
			)
			(layer "B.Fab")
		)
		(fp_line
			(start -0.4953 1.6002)
			(end 0.4953 1.6002)
			(stroke
				(width 0.1)
				(type default)
			)
			(layer "B.Fab")
		)
		(fp_line
			(start 0.4953 -0.2032)
			(end -0.4953 -0.2032)
			(stroke
				(width 0.1)
				(type default)
			)
			(layer "B.Fab")
		)
		(fp_line
			(start 0.4953 1.6002)
			(end 0.4953 -0.2032)
			(stroke
				(width 0.1)
				(type default)
			)
			(layer "B.Fab")
		)
		(pad "1" smd rect
			(at 0 0 180)
			(size 0.762 0.889)
			(layers "B.Cu" "B.Mask" "B.Paste")
			(net "P3V3_STBY")
		)
		(pad "2" smd rect
			(at 0 1.397 180)
			(size 0.762 0.889)
			(layers "B.Cu" "B.Mask" "B.Paste")
			(net "VCC_DACAV3V3")
		)
		(zone
			(layer "B.Cu")
			(hatch none 0.5)
			(connect_pads
				(clearance 0)
			)
			(min_thickness 0.25)
			(keepout
				(tracks allowed)
				(vias not_allowed)
				(pads allowed)
				(copperpour not_allowed)
				(footprints allowed)
			)
			(placement
				(enabled no)
				(sheetname "")
			)
			(fill
				(thermal_gap 0.5)
				(thermal_bridge_width 0.5)
				(island_removal_mode 0)
			)
			(polygon
				(pts
					(xy 399.970498 -33.830006) (xy 399.970498 -34.338006) (xy 400.732498 -34.338006) (xy 400.732498 -33.830006)
				)
			)
		)
		(zone
			(layer "B.Cu")
			(hatch none 0.5)
			(connect_pads
				(clearance 0)
			)
			(min_thickness 0.25)
			(keepout
				(tracks not_allowed)
				(vias allowed)
				(pads allowed)
				(copperpour not_allowed)
				(footprints allowed)
			)
			(placement
				(enabled no)
				(sheetname "")
			)
			(fill
				(thermal_gap 0.5)
				(thermal_bridge_width 0.5)
				(island_removal_mode 0)
			)
			(polygon
				(pts
					(xy 400.732498 -33.830006) (xy 400.732498 -34.338006) (xy 399.970498 -34.338006) (xy 399.970498 -33.830006)
				)
			)
		)
	)
)
